# S9S_MB_2U (Grand Teton) — schematic netlist excerpt (pin names and nets, part order shuffled) for the footprints in the layout excerpt that follows; sources: Cadence DE-HDL packaged netlist, KiCad conversion of 03242023_DA0F0TMBIJ0_F0T_Motherboard_J_brd_V01_OCP.brd

R3848  Q_RES  10K 1% CHIP  pkg 0402LF  page 163 : A = P3V3_AUX ; B = HP_LVC3_OCP_V3_2_P12V_PWRGD
R4746  Q_RES  33.2 1% CHIP  pkg 0402LF  page 158 : A = HP_LVC3_OCP_V3_1_PWRGD_R ; B = HP_LVC3_OCP_V3_1_PWRGD_R2

(kicad_pcb
	(version 20260206)
	(generator "pcbnew")
	(generator_version "10.0")
	(general
		(thickness 1.6)
		(legacy_teardrops no)
	)
	(paper "A4")
	(title_block
		(title "03242023_DA0F0TMBIJ0_F0T_Motherboard_J_brd_V01_OCP.brd")
		(comment 1 "Grand Teton / footprints 62-63 of 6105")
	)
	(layers
		(0 "F.Cu" signal "TOP")
		(4 "In1.Cu" signal "GND")
		(6 "In2.Cu" signal "IN1")
		(8 "In3.Cu" signal "GND1")
		(10 "In4.Cu" signal "IN2")
		(12 "In5.Cu" signal "GND2")
		(14 "In6.Cu" signal "IN3")
		(16 "In7.Cu" signal "GND3")
		(18 "In8.Cu" signal "VCC")
		(20 "In9.Cu" signal "VCC1")
		(22 "In10.Cu" signal "GND4")
		(24 "In11.Cu" signal "IN4")
		(26 "In12.Cu" signal "GND5")
		(28 "In13.Cu" signal "IN5")
		(30 "In14.Cu" signal "GND6")
		(32 "In15.Cu" signal "IN6")
		(34 "In16.Cu" signal "GND7")
		(2 "B.Cu" signal "BOTTOM")
		(9 "F.Adhes" user "F.Adhesive")
		(11 "B.Adhes" user "B.Adhesive")
		(13 "F.Paste" user "Package Geometry/Pastemask Top")
		(15 "B.Paste" user "Package Geometry/Pastemask Bottom")
		(5 "F.SilkS" user "Ref Des/Silkscreen Top")
		(7 "B.SilkS" user "Ref Des/Silkscreen Bottom")
		(1 "F.Mask" user "Board Geometry/Soldermask Top")
		(3 "B.Mask" user "Board Geometry/Soldermask Bottom")
		(17 "Dwgs.User" user "User.Drawings")
		(19 "Cmts.User" user "User.Comments")
		(21 "Eco1.User" user "User.Eco1")
		(23 "Eco2.User" user "User.Eco2")
		(25 "Edge.Cuts" user "Board Geometry/Outline")
		(27 "Margin" user)
		(31 "F.CrtYd" user "Package Geometry/Place Bound Top")
		(29 "B.CrtYd" user "Package Geometry/Place Bound Bottom")
		(35 "F.Fab" user "Ref Des/Assembly Top")
		(33 "B.Fab" user "Ref Des/Assembly Bottom")
	)
	(footprint ""
		(layer "F.Cu")
		(at 439.37174 -100.27158 90)
		(property "Reference" "R4746"
			(at 0 0 90)
			(layer "F.SilkS")
			(hide yes)
			(effects
				(font
					(size 1.27 1.27)
				)
			)
		)
		(property "Value" ""
			(at 0 0 90)
			(layer "F.Fab")
			(effects
				(font
					(size 1.27 1.27)
				)
			)
		)
		(duplicate_pad_numbers_are_jumpers no)
		(fp_line
			(start 0.7874 -0.4064)
			(end 0.7874 0.4064)
			(stroke
				(width 0.1524)
				(type default)
			)
			(layer "F.SilkS")
		)
		(fp_line
			(start -0.7874 -0.4064)
			(end 0.7874 -0.4064)
			(stroke
				(width 0.1524)
				(type default)
			)
			(layer "F.SilkS")
		)
		(fp_line
			(start 0.7874 0.4064)
			(end -0.7874 0.4064)
			(stroke
				(width 0.1524)
				(type default)
			)
			(layer "F.SilkS")
		)
		(fp_line
			(start -0.7874 0.4064)
			(end -0.7874 -0.4064)
			(stroke
				(width 0.1524)
				(type default)
			)
			(layer "F.SilkS")
		)
		(fp_line
			(start -0.12065 -0.305054)
			(end -0.12065 -0.2794)
			(stroke
				(width 0.1)
				(type default)
			)
			(layer "F.Fab")
		)
		(fp_line
			(start -0.67945 -0.305054)
			(end -0.12065 -0.305054)
			(stroke
				(width 0.1)
				(type default)
			)
			(layer "F.Fab")
		)
		(fp_line
			(start 0.67945 -0.3048)
			(end 0.67945 0.3048)
			(stroke
				(width 0.1)
				(type default)
			)
			(layer "F.Fab")
		)
		(fp_line
			(start 0.12065 -0.3048)
			(end 0.67945 -0.3048)
			(stroke
				(width 0.1)
				(type default)
			)
			(layer "F.Fab")
		)
		(fp_line
			(start 0.12065 -0.2794)
			(end 0.12065 -0.3048)
			(stroke
				(width 0.1)
				(type default)
			)
			(layer "F.Fab")
		)
		(fp_line
			(start -0.12065 -0.2794)
			(end 0.12065 -0.2794)
			(stroke
				(width 0.1)
				(type default)
			)
			(layer "F.Fab")
		)
		(fp_line
			(start 0.120396 0.2794)
			(end -0.12065 0.2794)
			(stroke
				(width 0.1)
				(type default)
			)
			(layer "F.Fab")
		)
		(fp_line
			(start -0.12065 0.2794)
			(end -0.12065 0.3048)
			(stroke
				(width 0.1)
				(type default)
			)
			(layer "F.Fab")
		)
		(fp_line
			(start 0.67945 0.3048)
			(end 0.120396 0.3048)
			(stroke
				(width 0.1)
				(type default)
			)
			(layer "F.Fab")
		)
		(fp_line
			(start 0.120396 0.3048)
			(end 0.120396 0.2794)
			(stroke
				(width 0.1)
				(type default)
			)
			(layer "F.Fab")
		)
		(fp_line
			(start -0.12065 0.3048)
			(end -0.67945 0.3048)
			(stroke
				(width 0.1)
				(type default)
			)
			(layer "F.Fab")
		)
		(fp_line
			(start -0.67945 0.3048)
			(end -0.67945 -0.305054)
			(stroke
				(width 0.1)
				(type default)
			)
			(layer "F.Fab")
		)
		(pad "1" smd circle
			(at -0.40005 0 90)
			(size 0 0)
			(layers "F.Cu" "F.Mask" "F.Paste")
			(net "HP_LVC3_OCP_V3_1_PWRGD_R")
		)
		(pad "2" smd circle
			(at 0.40005 0 90)
			(size 0 0)
			(layers "F.Cu" "F.Mask" "F.Paste")
			(net "HP_LVC3_OCP_V3_1_PWRGD_R2")
		)
	)
	(footprint ""
		(layer "F.Cu")
		(at 63.194438 -28.382722)
		(property "Reference" "R3848"
			(at 0 0 0)
			(layer "F.SilkS")
			(hide yes)
			(effects
				(font
					(size 1.27 1.27)
				)
			)
		)
		(property "Value" ""
			(at 0 0 0)
			(layer "F.Fab")
			(effects
				(font
					(size 1.27 1.27)
				)
			)
		)
		(duplicate_pad_numbers_are_jumpers no)
		(fp_line
			(start -0.7874 -0.4064)
			(end 0.7874 -0.4064)
			(stroke
				(width 0.1524)
				(type default)
			)
			(layer "F.SilkS")
		)
		(fp_line
			(start -0.7874 0.4064)
			(end -0.7874 -0.4064)
			(stroke
				(width 0.1524)
				(type default)
			)
			(layer "F.SilkS")
		)
		(fp_line
			(start 0.7874 -0.4064)
			(end 0.7874 0.4064)
			(stroke
				(width 0.1524)
				(type default)
			)
			(layer "F.SilkS")
		)
		(fp_line
			(start 0.7874 0.4064)
			(end -0.7874 0.4064)
			(stroke
				(width 0.1524)
				(type default)
			)
			(layer "F.SilkS")
		)
		(fp_line
			(start -0.67945 -0.305054)
			(end -0.12065 -0.305054)
			(stroke
				(width 0.1)
				(type default)
			)
			(layer "F.Fab")
		)
		(fp_line
			(start -0.67945 0.3048)
			(end -0.67945 -0.305054)
			(stroke
				(width 0.1)
				(type default)
			)
			(layer "F.Fab")
		)
		(fp_line
			(start -0.12065 -0.305054)
			(end -0.12065 -0.2794)
			(stroke
				(width 0.1)
				(type default)
			)
			(layer "F.Fab")
		)
		(fp_line
			(start -0.12065 -0.2794)
			(end 0.12065 -0.2794)
			(stroke
				(width 0.1)
				(type default)
			)
			(layer "F.Fab")
		)
		(fp_line
			(start -0.12065 0.2794)
			(end -0.12065 0.3048)
			(stroke
				(width 0.1)
				(type default)
			)
			(layer "F.Fab")
		)
		(fp_line
			(start -0.12065 0.3048)
			(end -0.67945 0.3048)
			(stroke
				(width 0.1)
				(type default)
			)
			(layer "F.Fab")
		)
		(fp_line
			(start 0.120396 0.2794)
			(end -0.12065 0.2794)
			(stroke
				(width 0.1)
				(type default)
			)
			(layer "F.Fab")
		)
		(fp_line
			(start 0.120396 0.3048)
			(end 0.120396 0.2794)
			(stroke
				(width 0.1)
				(type default)
			)
			(layer "F.Fab")
		)
		(fp_line
			(start 0.12065 -0.3048)
			(end 0.67945 -0.3048)
			(stroke
				(width 0.1)
				(type default)
			)
			(layer "F.Fab")
		)
		(fp_line
			(start 0.12065 -0.2794)
			(end 0.12065 -0.3048)
			(stroke
				(width 0.1)
				(type default)
			)
			(layer "F.Fab")
		)
		(fp_line
			(start 0.67945 -0.3048)
			(end 0.67945 0.3048)
			(stroke
				(width 0.1)
				(type default)
			)
			(layer "F.Fab")
		)
		(fp_line
			(start 0.67945 0.3048)
			(end 0.120396 0.3048)
			(stroke
				(width 0.1)
				(type default)
			)
			(layer "F.Fab")
		)
		(pad "1" smd circle
			(at -0.40005 0)
			(size 0 0)
			(layers "F.Cu" "F.Mask" "F.Paste")
			(net "P3V3_AUX")
		)
		(pad "2" smd circle
			(at 0.40005 0)
			(size 0 0)
			(layers "F.Cu" "F.Mask" "F.Paste")
			(net "HP_LVC3_OCP_V3_2_P12V_PWRGD")
		)
	)
)
